# BASEBOARD_FAB2 (Tioga Pass) — schematic netlist excerpt (pin names and nets, part order shuffled) for the footprints in the layout excerpt that follows; sources: Cadence DE-HDL packaged netlist, KiCad conversion of Wiwynn_Tioga_Pass_MB.brd

R4C4  RES  0.0 5% CHIP  pkg 0402  page 205 : A = VSENSE_PVSA_CPU0_P ; B = VSENSE_PVSA_CPU0_SKT_VSEN
R7A11  RES  0.0 5% CHIP  pkg 0402  page 218 : A = SVID_ALERT_PVDDQ_DEF ; B = SVID_ALERT1_CPU0_R_N
R8B15  RES  100.0 1% EMPTY  pkg 0402  page 236 : A = VSENSE_P1V05_PCH_STBY_AVSP ; B = VSENSE_P1V05_PCH_STBY_AVSN

(kicad_pcb
	(version 20260206)
	(generator "pcbnew")
	(generator_version "10.0")
	(general
		(thickness 1.6)
		(legacy_teardrops no)
	)
	(paper "A4")
	(title_block
		(title "Wiwynn_Tioga_Pass_MB.brd")
		(comment 1 "Tioga Pass / footprints 942-944 of 4770")
	)
	(layers
		(0 "F.Cu" signal "TOP")
		(4 "In1.Cu" signal "L2GND")
		(6 "In2.Cu" signal "L3")
		(8 "In3.Cu" signal "L4GND")
		(10 "In4.Cu" signal "L5")
		(12 "In5.Cu" signal "L6GND")
		(14 "In6.Cu" signal "L7VCC")
		(16 "In7.Cu" signal "L8VCC")
		(18 "In8.Cu" signal "L9GND")
		(20 "In9.Cu" signal "L10")
		(22 "In10.Cu" signal "L11GND")
		(24 "In11.Cu" signal "L12")
		(26 "In12.Cu" signal "L13GND")
		(2 "B.Cu" signal "BOTTOM")
		(9 "F.Adhes" user "F.Adhesive")
		(11 "B.Adhes" user "B.Adhesive")
		(13 "F.Paste" user "Package Geometry/Pastemask Top")
		(15 "B.Paste" user "Package Geometry/Pastemask Bottom")
		(5 "F.SilkS" user "Ref Des/Silkscreen Top")
		(7 "B.SilkS" user "Ref Des/Silkscreen Bottom")
		(1 "F.Mask" user "Board Geometry/Soldermask Top")
		(3 "B.Mask" user "Board Geometry/Soldermask Bottom")
		(17 "Dwgs.User" user "User.Drawings")
		(19 "Cmts.User" user "User.Comments")
		(21 "Eco1.User" user "User.Eco1")
		(23 "Eco2.User" user "User.Eco2")
		(25 "Edge.Cuts" user "Board Geometry/Outline")
		(27 "Margin" user)
		(31 "F.CrtYd" user "Package Geometry/Place Bound Top")
		(29 "B.CrtYd" user "Package Geometry/Place Bound Bottom")
		(35 "F.Fab" user "Ref Des/Assembly Top")
		(33 "B.Fab" user "Ref Des/Assembly Bottom")
	)
	(footprint ""
		(layer "F.Cu")
		(at 206.248 -102.616 90)
		(property "Reference" "R4C4"
			(at 0 0 90)
			(layer "F.SilkS")
			(hide yes)
			(effects
				(font
					(size 1.27 1.27)
				)
			)
		)
		(property "Value" ""
			(at 0 0 90)
			(layer "F.Fab")
			(effects
				(font
					(size 1.27 1.27)
				)
			)
		)
		(duplicate_pad_numbers_are_jumpers no)
		(fp_poly
			(pts
				(xy -0.2794 -0.1016) (xy 0.2794 -0.1016) (xy 0.2794 0.9906) (xy -0.2794 0.9906)
			)
			(stroke
				(width 0)
				(type default)
			)
			(fill no)
			(layer "F.CrtYd")
		)
		(fp_line
			(start 0.2794 -0.1016)
			(end -0.2794 -0.1016)
			(stroke
				(width 0.1)
				(type default)
			)
			(layer "F.Fab")
		)
		(fp_line
			(start -0.2794 -0.1016)
			(end -0.2794 0.9906)
			(stroke
				(width 0.1)
				(type default)
			)
			(layer "F.Fab")
		)
		(fp_line
			(start 0.2794 0.9906)
			(end 0.2794 -0.1016)
			(stroke
				(width 0.1)
				(type default)
			)
			(layer "F.Fab")
		)
		(fp_line
			(start -0.2794 0.9906)
			(end 0.2794 0.9906)
			(stroke
				(width 0.1)
				(type default)
			)
			(layer "F.Fab")
		)
		(pad "1" smd rect
			(at 0 0 90)
			(size 0.508 0.508)
			(layers "F.Cu" "F.Mask" "F.Paste")
			(net "VSENSE_PVSA_CPU0_P")
		)
		(pad "2" smd rect
			(at 0 0.889 90)
			(size 0.508 0.508)
			(layers "F.Cu" "F.Mask" "F.Paste")
			(net "VSENSE_PVSA_CPU0_SKT_VSEN")
		)
		(zone
			(layer "F.Cu")
			(hatch none 0.5)
			(connect_pads
				(clearance 0)
			)
			(min_thickness 0.25)
			(keepout
				(tracks allowed)
				(vias not_allowed)
				(pads allowed)
				(copperpour not_allowed)
				(footprints allowed)
			)
			(placement
				(enabled no)
				(sheetname "")
			)
			(fill
				(thermal_gap 0.5)
				(thermal_bridge_width 0.5)
				(island_removal_mode 0)
			)
			(polygon
				(pts
					(xy 206.502 -102.362) (xy 206.502 -102.87) (xy 206.883 -102.87) (xy 206.883 -102.362)
				)
			)
		)
		(zone
			(layer "F.Cu")
			(hatch none 0.5)
			(connect_pads
				(clearance 0)
			)
			(min_thickness 0.25)
			(keepout
				(tracks not_allowed)
				(vias allowed)
				(pads allowed)
				(copperpour not_allowed)
				(footprints allowed)
			)
			(placement
				(enabled no)
				(sheetname "")
			)
			(fill
				(thermal_gap 0.5)
				(thermal_bridge_width 0.5)
				(island_removal_mode 0)
			)
			(polygon
				(pts
					(xy 206.883 -102.362) (xy 206.883 -102.87) (xy 206.502 -102.87) (xy 206.502 -102.362)
				)
			)
		)
	)
	(footprint ""
		(layer "F.Cu")
		(at 412.085282 -125.863604)
		(property "Reference" "R8B15"
			(at 0 0 0)
			(layer "F.SilkS")
			(hide yes)
			(effects
				(font
					(size 1.27 1.27)
				)
			)
		)
		(property "Value" ""
			(at 0 0 0)
			(layer "F.Fab")
			(effects
				(font
					(size 1.27 1.27)
				)
			)
		)
		(duplicate_pad_numbers_are_jumpers no)
		(fp_poly
			(pts
				(xy -0.2794 -0.1016) (xy 0.2794 -0.1016) (xy 0.2794 0.9906) (xy -0.2794 0.9906)
			)
			(stroke
				(width 0)
				(type default)
			)
			(fill no)
			(layer "F.CrtYd")
		)
		(fp_line
			(start -0.2794 -0.1016)
			(end -0.2794 0.9906)
			(stroke
				(width 0.1)
				(type default)
			)
			(layer "F.Fab")
		)
		(fp_line
			(start -0.2794 0.9906)
			(end 0.2794 0.9906)
			(stroke
				(width 0.1)
				(type default)
			)
			(layer "F.Fab")
		)
		(fp_line
			(start 0.2794 -0.1016)
			(end -0.2794 -0.1016)
			(stroke
				(width 0.1)
				(type default)
			)
			(layer "F.Fab")
		)
		(fp_line
			(start 0.2794 0.9906)
			(end 0.2794 -0.1016)
			(stroke
				(width 0.1)
				(type default)
			)
			(layer "F.Fab")
		)
		(pad "1" smd rect
			(at 0 0)
			(size 0.508 0.508)
			(layers "F.Cu" "F.Mask" "F.Paste")
			(net "VSENSE_P1V05_PCH_STBY_AVSP")
		)
		(pad "2" smd rect
			(at 0 0.889)
			(size 0.508 0.508)
			(layers "F.Cu" "F.Mask" "F.Paste")
			(net "VSENSE_P1V05_PCH_STBY_AVSN")
		)
		(zone
			(layer "F.Cu")
			(hatch none 0.5)
			(connect_pads
				(clearance 0)
			)
			(min_thickness 0.25)
			(keepout
				(tracks allowed)
				(vias not_allowed)
				(pads allowed)
				(copperpour not_allowed)
				(footprints allowed)
			)
			(placement
				(enabled no)
				(sheetname "")
			)
			(fill
				(thermal_gap 0.5)
				(thermal_bridge_width 0.5)
				(island_removal_mode 0)
			)
			(polygon
				(pts
					(xy 411.831282 -125.609604) (xy 412.339282 -125.609604) (xy 412.339282 -125.228604) (xy 411.831282 -125.228604)
				)
			)
		)
		(zone
			(layer "F.Cu")
			(hatch none 0.5)
			(connect_pads
				(clearance 0)
			)
			(min_thickness 0.25)
			(keepout
				(tracks not_allowed)
				(vias allowed)
				(pads allowed)
				(copperpour not_allowed)
				(footprints allowed)
			)
			(placement
				(enabled no)
				(sheetname "")
			)
			(fill
				(thermal_gap 0.5)
				(thermal_bridge_width 0.5)
				(island_removal_mode 0)
			)
			(polygon
				(pts
					(xy 411.831282 -125.228604) (xy 412.339282 -125.228604) (xy 412.339282 -125.609604) (xy 411.831282 -125.609604)
				)
			)
		)
	)
	(footprint ""
		(layer "F.Cu")
		(at 363.87024 -139.30757 90)
		(property "Reference" "R7A11"
			(at 0 0 90)
			(layer "F.SilkS")
			(hide yes)
			(effects
				(font
					(size 1.27 1.27)
				)
			)
		)
		(property "Value" ""
			(at 0 0 90)
			(layer "F.Fab")
			(effects
				(font
					(size 1.27 1.27)
				)
			)
		)
		(duplicate_pad_numbers_are_jumpers no)
		(fp_rect
			(start -0.2794 -0.1016)
			(end 0.2794 0.9906)
			(stroke
				(width 0)
				(type default)
			)
			(fill no)
			(layer "F.CrtYd")
		)
		(fp_line
			(start 0.2794 -0.1016)
			(end -0.2794 -0.1016)
			(stroke
				(width 0.1)
				(type default)
			)
			(layer "F.Fab")
		)
		(fp_line
			(start -0.2794 -0.1016)
			(end -0.2794 0.9906)
			(stroke
				(width 0.1)
				(type default)
			)
			(layer "F.Fab")
		)
		(fp_line
			(start 0.2794 0.9906)
			(end 0.2794 -0.1016)
			(stroke
				(width 0.1)
				(type default)
			)
			(layer "F.Fab")
		)
		(fp_line
			(start -0.2794 0.9906)
			(end 0.2794 0.9906)
			(stroke
				(width 0.1)
				(type default)
			)
			(layer "F.Fab")
		)
		(pad "1" smd rect
			(at 0 0 90)
			(size 0.508 0.508)
			(layers "F.Cu" "F.Mask" "F.Paste")
			(net "SVID_ALERT_PVDDQ_DEF")
		)
		(pad "2" smd rect
			(at 0 0.889 90)
			(size 0.508 0.508)
			(layers "F.Cu" "F.Mask" "F.Paste")
			(net "SVID_ALERT1_CPU0_R_N")
		)
		(zone
			(layer "F.Cu")
			(hatch none 0.5)
			(connect_pads
				(clearance 0)
			)
			(min_thickness 0.25)
			(keepout
				(tracks allowed)
				(vias not_allowed)
				(pads allowed)
				(copperpour not_allowed)
				(footprints allowed)
			)
			(placement
				(enabled no)
				(sheetname "")
			)
			(fill
				(thermal_gap 0.5)
				(thermal_bridge_width 0.5)
				(island_removal_mode 0)
			)
			(polygon
				(pts
					(xy 364.12424 -139.05357) (xy 364.50524 -139.05357) (xy 364.50524 -139.56157) (xy 364.12424 -139.56157)
				)
			)
		)
		(zone
			(layer "F.Cu")
			(hatch none 0.5)
			(connect_pads
				(clearance 0)
			)
			(min_thickness 0.25)
			(keepout
				(tracks not_allowed)
				(vias allowed)
				(pads allowed)
				(copperpour not_allowed)
				(footprints allowed)
			)
			(placement
				(enabled no)
				(sheetname "")
			)
			(fill
				(thermal_gap 0.5)
				(thermal_bridge_width 0.5)
				(island_removal_mode 0)
			)
			(polygon
				(pts
					(xy 364.12424 -139.05357) (xy 364.50524 -139.05357) (xy 364.50524 -139.56157) (xy 364.12424 -139.56157)
				)
			)
		)
	)
)
